# S9S_MB_2U (Grand Teton) — schematic netlist excerpt (pin names and nets, part order shuffled) for the footprints in the layout excerpt that follows; sources: Cadence DE-HDL packaged netlist, KiCad conversion of 03242023_DA0F0TMBIJ0_F0T_Motherboard_J_brd_V01_OCP.brd

R2457  Q_RES  100K 1% CHIP  pkg 0402LF  page 191 : A = E1S_0_EN ; B = GND
C1549  Q_CAP_DIFFBUS  DIFF BUS_0.22UF 6.3V 20% X6S  pkg C0201  page 175 : \1\ = P5E_CPU0_PE4_TX_C_DP<15> ; \2\ = P5E_CPU0_PE4_TX_DP<15>
PC1673  Q_CAP  22UF 16V 20% X6S  pkg C0805  page 272 : A = SW_P12V_PVCCFA_EHV_FIVRA_CPU0_R ; B = GND

(kicad_pcb
	(version 20260206)
	(generator "pcbnew")
	(generator_version "10.0")
	(general
		(thickness 1.6)
		(legacy_teardrops no)
	)
	(paper "A4")
	(title_block
		(title "03242023_DA0F0TMBIJ0_F0T_Motherboard_J_brd_V01_OCP.brd")
		(comment 1 "Grand Teton / footprints 119-121 of 6105")
	)
	(layers
		(0 "F.Cu" signal "TOP")
		(4 "In1.Cu" signal "GND")
		(6 "In2.Cu" signal "IN1")
		(8 "In3.Cu" signal "GND1")
		(10 "In4.Cu" signal "IN2")
		(12 "In5.Cu" signal "GND2")
		(14 "In6.Cu" signal "IN3")
		(16 "In7.Cu" signal "GND3")
		(18 "In8.Cu" signal "VCC")
		(20 "In9.Cu" signal "VCC1")
		(22 "In10.Cu" signal "GND4")
		(24 "In11.Cu" signal "IN4")
		(26 "In12.Cu" signal "GND5")
		(28 "In13.Cu" signal "IN5")
		(30 "In14.Cu" signal "GND6")
		(32 "In15.Cu" signal "IN6")
		(34 "In16.Cu" signal "GND7")
		(2 "B.Cu" signal "BOTTOM")
		(9 "F.Adhes" user "F.Adhesive")
		(11 "B.Adhes" user "B.Adhesive")
		(13 "F.Paste" user "Package Geometry/Pastemask Top")
		(15 "B.Paste" user "Package Geometry/Pastemask Bottom")
		(5 "F.SilkS" user "Ref Des/Silkscreen Top")
		(7 "B.SilkS" user "Ref Des/Silkscreen Bottom")
		(1 "F.Mask" user "Board Geometry/Soldermask Top")
		(3 "B.Mask" user "Board Geometry/Soldermask Bottom")
		(17 "Dwgs.User" user "User.Drawings")
		(19 "Cmts.User" user "User.Comments")
		(21 "Eco1.User" user "User.Eco1")
		(23 "Eco2.User" user "User.Eco2")
		(25 "Edge.Cuts" user "Board Geometry/Outline")
		(27 "Margin" user)
		(31 "F.CrtYd" user "Package Geometry/Place Bound Top")
		(29 "B.CrtYd" user "Package Geometry/Place Bound Bottom")
		(35 "F.Fab" user "Ref Des/Assembly Top")
		(33 "B.Fab" user "Ref Des/Assembly Bottom")
	)
	(footprint ""
		(layer "F.Cu")
		(at 350.817688 -402.371052 -90)
		(property "Reference" "C1549"
			(at 0 0 270)
			(layer "F.SilkS")
			(hide yes)
			(effects
				(font
					(size 1.27 1.27)
				)
			)
		)
		(property "Value" ""
			(at 0 0 270)
			(layer "F.Fab")
			(effects
				(font
					(size 1.27 1.27)
				)
			)
		)
		(duplicate_pad_numbers_are_jumpers no)
		(fp_line
			(start -0.299974 0.150114)
			(end -0.299974 -0.150114)
			(stroke
				(width 0.1)
				(type default)
			)
			(layer "F.Fab")
		)
		(fp_line
			(start 0.299974 0.150114)
			(end -0.299974 0.150114)
			(stroke
				(width 0.1)
				(type default)
			)
			(layer "F.Fab")
		)
		(fp_line
			(start -0.299974 -0.150114)
			(end 0.299974 -0.150114)
			(stroke
				(width 0.1)
				(type default)
			)
			(layer "F.Fab")
		)
		(fp_line
			(start 0.299974 -0.150114)
			(end 0.299974 0.150114)
			(stroke
				(width 0.1)
				(type default)
			)
			(layer "F.Fab")
		)
		(pad "1" smd rect
			(at -0.2667 0 270)
			(size 0.3048 0.381)
			(layers "F.Cu" "F.Mask" "F.Paste")
			(net "P5E_CPU0_PE4_TX_C_DP<15>")
		)
		(pad "2" smd rect
			(at 0.2667 0 270)
			(size 0.3048 0.381)
			(layers "F.Cu" "F.Mask" "F.Paste")
			(net "P5E_CPU0_PE4_TX_DP<15>")
		)
	)
	(footprint ""
		(layer "F.Cu")
		(at 149.368256 -64.059308)
		(property "Reference" "R2457"
			(at 0 0 0)
			(layer "F.SilkS")
			(hide yes)
			(effects
				(font
					(size 1.27 1.27)
				)
			)
		)
		(property "Value" ""
			(at 0 0 0)
			(layer "F.Fab")
			(effects
				(font
					(size 1.27 1.27)
				)
			)
		)
		(duplicate_pad_numbers_are_jumpers no)
		(fp_line
			(start -0.7874 -0.4064)
			(end 0.7874 -0.4064)
			(stroke
				(width 0.1524)
				(type default)
			)
			(layer "F.SilkS")
		)
		(fp_line
			(start -0.7874 0.4064)
			(end -0.7874 -0.4064)
			(stroke
				(width 0.1524)
				(type default)
			)
			(layer "F.SilkS")
		)
		(fp_line
			(start 0.7874 -0.4064)
			(end 0.7874 0.4064)
			(stroke
				(width 0.1524)
				(type default)
			)
			(layer "F.SilkS")
		)
		(fp_line
			(start 0.7874 0.4064)
			(end -0.7874 0.4064)
			(stroke
				(width 0.1524)
				(type default)
			)
			(layer "F.SilkS")
		)
		(fp_line
			(start -0.67945 -0.305054)
			(end -0.12065 -0.305054)
			(stroke
				(width 0.1)
				(type default)
			)
			(layer "F.Fab")
		)
		(fp_line
			(start -0.67945 0.3048)
			(end -0.67945 -0.305054)
			(stroke
				(width 0.1)
				(type default)
			)
			(layer "F.Fab")
		)
		(fp_line
			(start -0.12065 -0.305054)
			(end -0.12065 -0.2794)
			(stroke
				(width 0.1)
				(type default)
			)
			(layer "F.Fab")
		)
		(fp_line
			(start -0.12065 -0.2794)
			(end 0.12065 -0.2794)
			(stroke
				(width 0.1)
				(type default)
			)
			(layer "F.Fab")
		)
		(fp_line
			(start -0.12065 0.2794)
			(end -0.12065 0.3048)
			(stroke
				(width 0.1)
				(type default)
			)
			(layer "F.Fab")
		)
		(fp_line
			(start -0.12065 0.3048)
			(end -0.67945 0.3048)
			(stroke
				(width 0.1)
				(type default)
			)
			(layer "F.Fab")
		)
		(fp_line
			(start 0.120396 0.2794)
			(end -0.12065 0.2794)
			(stroke
				(width 0.1)
				(type default)
			)
			(layer "F.Fab")
		)
		(fp_line
			(start 0.120396 0.3048)
			(end 0.120396 0.2794)
			(stroke
				(width 0.1)
				(type default)
			)
			(layer "F.Fab")
		)
		(fp_line
			(start 0.12065 -0.3048)
			(end 0.67945 -0.3048)
			(stroke
				(width 0.1)
				(type default)
			)
			(layer "F.Fab")
		)
		(fp_line
			(start 0.12065 -0.2794)
			(end 0.12065 -0.3048)
			(stroke
				(width 0.1)
				(type default)
			)
			(layer "F.Fab")
		)
		(fp_line
			(start 0.67945 -0.3048)
			(end 0.67945 0.3048)
			(stroke
				(width 0.1)
				(type default)
			)
			(layer "F.Fab")
		)
		(fp_line
			(start 0.67945 0.3048)
			(end 0.120396 0.3048)
			(stroke
				(width 0.1)
				(type default)
			)
			(layer "F.Fab")
		)
		(pad "1" smd circle
			(at -0.40005 0)
			(size 0 0)
			(layers "F.Cu" "F.Mask" "F.Paste")
			(net "E1S_0_EN")
		)
		(pad "2" smd circle
			(at 0.40005 0)
			(size 0 0)
			(layers "F.Cu" "F.Mask" "F.Paste")
			(net "GND")
		)
	)
	(footprint ""
		(layer "F.Cu")
		(at 431.062638 -368.79149)
		(property "Reference" "PC1673"
			(at 0 0 0)
			(layer "F.SilkS")
			(hide yes)
			(effects
				(font
					(size 1.27 1.27)
				)
			)
		)
		(property "Value" ""
			(at 0 0 0)
			(layer "F.Fab")
			(effects
				(font
					(size 1.27 1.27)
				)
			)
		)
		(duplicate_pad_numbers_are_jumpers no)
		(fp_line
			(start -1.524 -0.762)
			(end 1.524 -0.762)
			(stroke
				(width 0.1524)
				(type default)
			)
			(layer "F.SilkS")
		)
		(fp_line
			(start -1.524 0.762)
			(end -1.524 -0.762)
			(stroke
				(width 0.1524)
				(type default)
			)
			(layer "F.SilkS")
		)
		(fp_line
			(start 1.524 -0.762)
			(end 1.524 0.762)
			(stroke
				(width 0.1524)
				(type default)
			)
			(layer "F.SilkS")
		)
		(fp_line
			(start 1.524 0.762)
			(end -1.524 0.762)
			(stroke
				(width 0.1524)
				(type default)
			)
			(layer "F.SilkS")
		)
		(fp_line
			(start -1.1049 -0.724916)
			(end -1.1049 0.724916)
			(stroke
				(width 0.1)
				(type default)
			)
			(layer "F.Fab")
		)
		(fp_line
			(start -1.1049 0.724916)
			(end 1.1049 0.724916)
			(stroke
				(width 0.1)
				(type default)
			)
			(layer "F.Fab")
		)
		(fp_line
			(start 1.1049 -0.724916)
			(end -1.1049 -0.724916)
			(stroke
				(width 0.1)
				(type default)
			)
			(layer "F.Fab")
		)
		(fp_line
			(start 1.1049 0.724916)
			(end 1.1049 -0.724916)
			(stroke
				(width 0.1)
				(type default)
			)
			(layer "F.Fab")
		)
		(pad "1" smd rect
			(at -0.889 0 180)
			(size 1.016 1.27)
			(layers "F.Cu" "F.Mask" "F.Paste")
			(net "SW_P12V_PVCCFA_EHV_FIVRA_CPU0_R")
		)
		(pad "2" smd rect
			(at 0.889 0 180)
			(size 1.016 1.27)
			(layers "F.Cu" "F.Mask" "F.Paste")
			(net "GND")
		)
	)
)
